# T6G (Grand Teton) — schematic netlist excerpt (pin names and nets, part order shuffled) for the footprints in the layout excerpt that follows; sources: Cadence DE-HDL packaged netlist, KiCad conversion of 04192023_DAF0TMB3IC0_F0TG_MB_C_brd_V02_OCP.brd

R8112  Q_RES  1M 1% EMPTY  pkg 0402LF  page 267 : A = HSC_OC_VOL ; B = HSC_D_OC_R2
C3913  Q_CAP  22UF 4V 20% X6S  pkg C0402  page 74 : A = PVDDCR_SOC_P1 ; B = GND

(kicad_pcb
	(version 20260206)
	(generator "pcbnew")
	(generator_version "10.0")
	(general
		(thickness 1.6)
		(legacy_teardrops no)
	)
	(paper "A4")
	(title_block
		(title "04192023_DAF0TMB3IC0_F0TG_MB_C_brd_V02_OCP.brd")
		(comment 1 "Grand Teton / footprints 5826-5827 of 8354")
	)
	(layers
		(0 "F.Cu" signal "TOP")
		(4 "In1.Cu" signal "GND")
		(6 "In2.Cu" signal "IN1")
		(8 "In3.Cu" signal "GND1")
		(10 "In4.Cu" signal "IN2")
		(12 "In5.Cu" signal "GND2")
		(14 "In6.Cu" signal "IN3")
		(16 "In7.Cu" signal "GND3")
		(18 "In8.Cu" signal "VCC")
		(20 "In9.Cu" signal "VCC1")
		(22 "In10.Cu" signal "GND4")
		(24 "In11.Cu" signal "IN4")
		(26 "In12.Cu" signal "GND5")
		(28 "In13.Cu" signal "IN5")
		(30 "In14.Cu" signal "GND6")
		(32 "In15.Cu" signal "IN6")
		(34 "In16.Cu" signal "GND7")
		(2 "B.Cu" signal "BOTTOM")
		(9 "F.Adhes" user "F.Adhesive")
		(11 "B.Adhes" user "B.Adhesive")
		(13 "F.Paste" user "Package Geometry/Pastemask Top")
		(15 "B.Paste" user "Package Geometry/Pastemask Bottom")
		(5 "F.SilkS" user "Ref Des/Silkscreen Top")
		(7 "B.SilkS" user "Ref Des/Silkscreen Bottom")
		(1 "F.Mask" user "Board Geometry/Soldermask Top")
		(3 "B.Mask" user "Board Geometry/Soldermask Bottom")
		(17 "Dwgs.User" user "User.Drawings")
		(19 "Cmts.User" user "User.Comments")
		(21 "Eco1.User" user "User.Eco1")
		(23 "Eco2.User" user "User.Eco2")
		(25 "Edge.Cuts" user "Board Geometry/Outline")
		(27 "Margin" user)
		(31 "F.CrtYd" user "Package Geometry/Place Bound Top")
		(29 "B.CrtYd" user "Package Geometry/Place Bound Bottom")
		(35 "F.Fab" user "Ref Des/Assembly Top")
		(33 "B.Fab" user "Ref Des/Assembly Bottom")
	)
	(footprint ""
		(layer "B.Cu")
		(at 124.373386 -261.04723)
		(property "Reference" "C3913"
			(at 0 0 0)
			(layer "B.SilkS")
			(hide yes)
			(effects
				(font
					(size 1.27 1.27)
				)
				(justify mirror)
			)
		)
		(property "Value" ""
			(at 0 0 0)
			(layer "B.Fab")
			(effects
				(font
					(size 1.27 1.27)
				)
				(justify mirror)
			)
		)
		(duplicate_pad_numbers_are_jumpers no)
		(fp_line
			(start -0.7874 -0.4064)
			(end -0.7874 0.4064)
			(stroke
				(width 0.1524)
				(type default)
			)
			(layer "B.SilkS")
		)
		(fp_line
			(start -0.7874 0.4064)
			(end 0.7874 0.4064)
			(stroke
				(width 0.1524)
				(type default)
			)
			(layer "B.SilkS")
		)
		(fp_line
			(start 0.7874 -0.4064)
			(end -0.7874 -0.4064)
			(stroke
				(width 0.1524)
				(type default)
			)
			(layer "B.SilkS")
		)
		(fp_line
			(start 0.7874 0.4064)
			(end 0.7874 -0.4064)
			(stroke
				(width 0.1524)
				(type default)
			)
			(layer "B.SilkS")
		)
		(fp_line
			(start -0.67945 -0.3048)
			(end -0.67945 0.3048)
			(stroke
				(width 0.1)
				(type default)
			)
			(layer "B.Fab")
		)
		(fp_line
			(start -0.67945 0.3048)
			(end -0.120396 0.3048)
			(stroke
				(width 0.1)
				(type default)
			)
			(layer "B.Fab")
		)
		(fp_line
			(start -0.12065 -0.3048)
			(end -0.67945 -0.3048)
			(stroke
				(width 0.1)
				(type default)
			)
			(layer "B.Fab")
		)
		(fp_line
			(start -0.12065 -0.2794)
			(end -0.12065 -0.3048)
			(stroke
				(width 0.1)
				(type default)
			)
			(layer "B.Fab")
		)
		(fp_line
			(start -0.120396 0.2794)
			(end 0.12065 0.2794)
			(stroke
				(width 0.1)
				(type default)
			)
			(layer "B.Fab")
		)
		(fp_line
			(start -0.120396 0.3048)
			(end -0.120396 0.2794)
			(stroke
				(width 0.1)
				(type default)
			)
			(layer "B.Fab")
		)
		(fp_line
			(start 0.12065 -0.305054)
			(end 0.12065 -0.2794)
			(stroke
				(width 0.1)
				(type default)
			)
			(layer "B.Fab")
		)
		(fp_line
			(start 0.12065 -0.2794)
			(end -0.12065 -0.2794)
			(stroke
				(width 0.1)
				(type default)
			)
			(layer "B.Fab")
		)
		(fp_line
			(start 0.12065 0.2794)
			(end 0.12065 0.3048)
			(stroke
				(width 0.1)
				(type default)
			)
			(layer "B.Fab")
		)
		(fp_line
			(start 0.12065 0.3048)
			(end 0.67945 0.3048)
			(stroke
				(width 0.1)
				(type default)
			)
			(layer "B.Fab")
		)
		(fp_line
			(start 0.67945 -0.305054)
			(end 0.12065 -0.305054)
			(stroke
				(width 0.1)
				(type default)
			)
			(layer "B.Fab")
		)
		(fp_line
			(start 0.67945 0.3048)
			(end 0.67945 -0.305054)
			(stroke
				(width 0.1)
				(type default)
			)
			(layer "B.Fab")
		)
		(pad "1" smd circle
			(at 0.40005 0 180)
			(size 0 0)
			(layers "B.Cu" "B.Mask" "B.Paste")
			(net "PVDDCR_SOC_P1")
		)
		(pad "2" smd circle
			(at -0.40005 0 180)
			(size 0 0)
			(layers "B.Cu" "B.Mask" "B.Paste")
			(net "GND")
		)
	)
	(footprint ""
		(layer "B.Cu")
		(at 184.719468 -425.467526 -90)
		(property "Reference" "R8112"
			(at 0 0 90)
			(layer "B.SilkS")
			(hide yes)
			(effects
				(font
					(size 1.27 1.27)
				)
				(justify mirror)
			)
		)
		(property "Value" ""
			(at 0 0 90)
			(layer "B.Fab")
			(effects
				(font
					(size 1.27 1.27)
				)
				(justify mirror)
			)
		)
		(duplicate_pad_numbers_are_jumpers no)
		(fp_line
			(start -0.7874 0.4064)
			(end 0.7874 0.4064)
			(stroke
				(width 0.1524)
				(type default)
			)
			(layer "B.SilkS")
		)
		(fp_line
			(start 0.7874 0.4064)
			(end 0.7874 -0.4064)
			(stroke
				(width 0.1524)
				(type default)
			)
			(layer "B.SilkS")
		)
		(fp_line
			(start -0.7874 -0.4064)
			(end -0.7874 0.4064)
			(stroke
				(width 0.1524)
				(type default)
			)
			(layer "B.SilkS")
		)
		(fp_line
			(start 0.7874 -0.4064)
			(end -0.7874 -0.4064)
			(stroke
				(width 0.1524)
				(type default)
			)
			(layer "B.SilkS")
		)
		(fp_line
			(start -0.67945 0.3048)
			(end -0.120396 0.3048)
			(stroke
				(width 0.1)
				(type default)
			)
			(layer "B.Fab")
		)
		(fp_line
			(start -0.120396 0.3048)
			(end -0.120396 0.2794)
			(stroke
				(width 0.1)
				(type default)
			)
			(layer "B.Fab")
		)
		(fp_line
			(start 0.12065 0.3048)
			(end 0.67945 0.3048)
			(stroke
				(width 0.1)
				(type default)
			)
			(layer "B.Fab")
		)
		(fp_line
			(start 0.67945 0.3048)
			(end 0.67945 -0.305054)
			(stroke
				(width 0.1)
				(type default)
			)
			(layer "B.Fab")
		)
		(fp_line
			(start -0.120396 0.2794)
			(end 0.12065 0.2794)
			(stroke
				(width 0.1)
				(type default)
			)
			(layer "B.Fab")
		)
		(fp_line
			(start 0.12065 0.2794)
			(end 0.12065 0.3048)
			(stroke
				(width 0.1)
				(type default)
			)
			(layer "B.Fab")
		)
		(fp_line
			(start -0.12065 -0.2794)
			(end -0.12065 -0.3048)
			(stroke
				(width 0.1)
				(type default)
			)
			(layer "B.Fab")
		)
		(fp_line
			(start 0.12065 -0.2794)
			(end -0.12065 -0.2794)
			(stroke
				(width 0.1)
				(type default)
			)
			(layer "B.Fab")
		)
		(fp_line
			(start -0.67945 -0.3048)
			(end -0.67945 0.3048)
			(stroke
				(width 0.1)
				(type default)
			)
			(layer "B.Fab")
		)
		(fp_line
			(start -0.12065 -0.3048)
			(end -0.67945 -0.3048)
			(stroke
				(width 0.1)
				(type default)
			)
			(layer "B.Fab")
		)
		(fp_line
			(start 0.12065 -0.305054)
			(end 0.12065 -0.2794)
			(stroke
				(width 0.1)
				(type default)
			)
			(layer "B.Fab")
		)
		(fp_line
			(start 0.67945 -0.305054)
			(end 0.12065 -0.305054)
			(stroke
				(width 0.1)
				(type default)
			)
			(layer "B.Fab")
		)
		(pad "1" smd circle
			(at 0.40005 0 90)
			(size 0 0)
			(layers "B.Cu" "B.Mask" "B.Paste")
			(net "HSC_OC_VOL")
		)
		(pad "2" smd circle
			(at -0.40005 0 90)
			(size 0 0)
			(layers "B.Cu" "B.Mask" "B.Paste")
			(net "HSC_D_OC_R2")
		)
	)
)
